# TIMECARD (Time Appliance Project (Time Card)) — schematic netlist excerpt (pin names and nets, part order shuffled) for the footprints in the layout excerpt that follows; sources: Cadence DE-HDL packaged netlist, KiCad conversion of R4006-B0001-02_R01.brd

MAC_PIN6  NUT  pkg P_NUT_079C100  page 21 : \1\ = R_MAC_BITEOUT
SP38  SOLDER_PREFORM  pkg 0201_SOLDER_PREFORM_4MIL  page 34 : \1\ = NC ; \2\ = NC
R143  RESISTOR  33OHM 1%  pkg SMC_0402R_H016  page 31 : \1\ = FPGA_CFG_INIT_N ; \2\ = UNNAMED_515_NCP45560IMNTWGHDFN1

(kicad_pcb
	(version 20260206)
	(generator "pcbnew")
	(generator_version "10.0")
	(general
		(thickness 1.6)
		(legacy_teardrops no)
	)
	(paper "A4")
	(title_block
		(title "timecard-production-celestica-r4006 — R4006-B0001-02_R01.brd")
		(comment 1 "Time Appliance Project (Time Card) / footprints 263-265 of 1113")
	)
	(layers
		(0 "F.Cu" signal "TOP")
		(4 "In1.Cu" signal "L02_GND1")
		(6 "In2.Cu" signal "L03_SIG1")
		(8 "In3.Cu" signal "L04_GND2")
		(10 "In4.Cu" signal "L05_VCC1")
		(12 "In5.Cu" signal "L06_VCC2")
		(14 "In6.Cu" signal "L07_GND3")
		(16 "In7.Cu" signal "L08_SIG2")
		(18 "In8.Cu" signal "L09_GND4")
		(2 "B.Cu" signal "BOTTOM")
		(9 "F.Adhes" user "F.Adhesive")
		(11 "B.Adhes" user "B.Adhesive")
		(13 "F.Paste" user "Package Geometry/Pastemask Top")
		(15 "B.Paste" user "Package Geometry/Pastemask Bottom")
		(5 "F.SilkS" user "Ref Des/Silkscreen Top")
		(7 "B.SilkS" user "Ref Des/Silkscreen Bottom")
		(1 "F.Mask" user "Board Geometry/Soldermask Top")
		(3 "B.Mask" user "Board Geometry/Soldermask Bottom")
		(17 "Dwgs.User" user "User.Drawings")
		(19 "Cmts.User" user "User.Comments")
		(21 "Eco1.User" user "User.Eco1")
		(23 "Eco2.User" user "User.Eco2")
		(25 "Edge.Cuts" user "Board Geometry/Outline")
		(27 "Margin" user)
		(31 "F.CrtYd" user "Package Geometry/Place Bound Top")
		(29 "B.CrtYd" user "Package Geometry/Place Bound Bottom")
		(35 "F.Fab" user "Ref Des/Assembly Top")
		(33 "B.Fab" user "Ref Des/Assembly Bottom")
	)
	(footprint ""
		(layer "F.Cu")
		(at 70.578218 -23.734522)
		(property "Reference" "MAC_PIN6"
			(at 2.667762 2.580132 0)
			(unlocked yes)
			(layer "F.SilkS")
			(effects
				(font
					(size 0.7874 0.5842)
					(thickness 0.1524)
				)
			)
		)
		(property "Value" ""
			(at 0 0 0)
			(layer "F.Fab")
			(effects
				(font
					(size 1.27 1.27)
				)
			)
		)
		(property "Device Type" "NUT-A200-00029-FB"
			(at 0 2.632964 0)
			(unlocked yes)
			(layer "F.Fab")
			(hide yes)
			(effects
				(font
					(size 0.7874 0.5842)
					(thickness 0.1524)
				)
			)
		)
		(property "User Part Number" "PARTNUM*"
			(at 0 3.826764 0)
			(unlocked yes)
			(layer "Cmts.User")
			(hide yes)
			(effects
				(font
					(size 0.7874 0.5842)
					(thickness 0.1524)
				)
			)
		)
		(duplicate_pad_numbers_are_jumpers no)
		(fp_circle
			(center 0 0)
			(end 1.524 0)
			(stroke
				(width 0.1)
				(type default)
			)
			(fill no)
			(layer "F.SilkS")
		)
		(fp_poly
			(pts
				(arc
					(start -1.260856 -0.1524)
					(mid -0.898049 -0.898049)
					(end -0.1524 -1.260856)
				)
				(arc
					(start -0.1524 -0.991616)
					(mid -0.709411 -0.709411)
					(end -0.991616 -0.1524)
				)
			)
			(stroke
				(width 0)
				(type default)
			)
			(fill yes)
			(layer "F.Paste")
		)
		(fp_poly
			(pts
				(arc
					(start -0.1524 1.260856)
					(mid -0.898049 0.898049)
					(end -1.260856 0.1524)
				)
				(arc
					(start -0.991616 0.1524)
					(mid -0.709411 0.709411)
					(end -0.1524 0.991616)
				)
			)
			(stroke
				(width 0)
				(type default)
			)
			(fill yes)
			(layer "F.Paste")
		)
		(fp_poly
			(pts
				(arc
					(start 0.1524 -1.260856)
					(mid 0.898049 -0.898049)
					(end 1.260856 -0.1524)
				)
				(arc
					(start 0.991616 -0.1524)
					(mid 0.709411 -0.709411)
					(end 0.1524 -0.991616)
				)
			)
			(stroke
				(width 0)
				(type default)
			)
			(fill yes)
			(layer "F.Paste")
		)
		(fp_poly
			(pts
				(arc
					(start 1.260856 0.1524)
					(mid 0.898049 0.898049)
					(end 0.1524 1.260856)
				)
				(arc
					(start 0.1524 0.991616)
					(mid 0.709411 0.709411)
					(end 0.991616 0.1524)
				)
			)
			(stroke
				(width 0)
				(type default)
			)
			(fill yes)
			(layer "F.Paste")
		)
		(fp_poly
			(pts
				(arc
					(start 6.35 0)
					(mid -6.35 0)
					(end 6.35 0)
				)
			)
			(stroke
				(width 0)
				(type default)
			)
			(fill no)
			(layer "B.CrtYd")
		)
		(fp_poly
			(pts
				(arc
					(start 1.778 0)
					(mid -1.778 0)
					(end 1.778 0)
				)
			)
			(stroke
				(width 0)
				(type default)
			)
			(fill no)
			(layer "F.CrtYd")
		)
		(fp_circle
			(center 0 0)
			(end 1.1684 0)
			(stroke
				(width 0.1)
				(type default)
			)
			(fill no)
			(layer "F.Fab")
		)
		(pad "1" thru_hole circle
			(at 0 0)
			(size 2.54 2.54)
			(drill 2.0066)
			(layers "*.Cu" "*.Mask")
			(remove_unused_layers no)
			(net "R_MAC_BITEOUT")
			(thermal_gap 0.0254)
			(padstack
				(mode front_inner_back)
				(layer "Inner"
					(shape circle)
					(size 2.54 2.54)
					(clearance 0.0254)
				)
				(layer "B.Cu"
					(shape circle)
					(size 2.54 2.54)
				)
			)
		)
	)
	(footprint ""
		(layer "F.Cu")
		(at 115.443 -76.073 180)
		(property "Reference" "R143"
			(at -3.429 0.46863 0)
			(unlocked yes)
			(layer "F.SilkS")
			(effects
				(font
					(size 0.7874 0.5842)
					(thickness 0.1524)
				)
			)
		)
		(property "Value" "VAL*"
			(at 0.02032 2.13233 180)
			(unlocked yes)
			(layer "F.Fab")
			(hide yes)
			(effects
				(font
					(size 0.7874 0.5842)
					(thickness 0.1524)
				)
			)
		)
		(property "Device Type" "RESISTOR-G155-133R0-01,33OHM,1%"
			(at 0.008382 1.210564 180)
			(unlocked yes)
			(layer "F.Fab")
			(hide yes)
			(effects
				(font
					(size 0.7874 0.5842)
					(thickness 0.1524)
				)
			)
		)
		(property "User Part Number" "PARTNUM*"
			(at 0.02032 4.024884 180)
			(unlocked yes)
			(layer "Cmts.User")
			(hide yes)
			(effects
				(font
					(size 0.7874 0.5842)
					(thickness 0.1524)
				)
			)
		)
		(property "Tolerance" "TOL*"
			(at 0.044704 3.05435 180)
			(unlocked yes)
			(layer "Cmts.User")
			(hide yes)
			(effects
				(font
					(size 0.7874 0.5842)
					(thickness 0.1524)
				)
			)
		)
		(duplicate_pad_numbers_are_jumpers no)
		(fp_line
			(start 1.143 0.5588)
			(end 1.143 -0.5588)
			(stroke
				(width 0.1)
				(type default)
			)
			(layer "F.SilkS")
		)
		(fp_line
			(start 1.143 -0.5588)
			(end -1.143 -0.5588)
			(stroke
				(width 0.1)
				(type default)
			)
			(layer "F.SilkS")
		)
		(fp_line
			(start -1.143 0.5588)
			(end 1.143 0.5588)
			(stroke
				(width 0.1)
				(type default)
			)
			(layer "F.SilkS")
		)
		(fp_line
			(start -1.143 -0.5588)
			(end -1.143 0.5588)
			(stroke
				(width 0.1)
				(type default)
			)
			(layer "F.SilkS")
		)
		(fp_rect
			(start 1.143 0.5588)
			(end -1.143 -0.5588)
			(stroke
				(width 0)
				(type default)
			)
			(fill no)
			(layer "F.CrtYd")
		)
		(fp_line
			(start 0.508 0.3048)
			(end 0.508 -0.3048)
			(stroke
				(width 0.1)
				(type default)
			)
			(layer "F.Fab")
		)
		(fp_line
			(start 0.508 -0.3048)
			(end -0.508 -0.3048)
			(stroke
				(width 0.1)
				(type default)
			)
			(layer "F.Fab")
		)
		(fp_line
			(start -0.508 0.3048)
			(end 0.508 0.3048)
			(stroke
				(width 0.1)
				(type default)
			)
			(layer "F.Fab")
		)
		(fp_line
			(start -0.508 -0.3048)
			(end -0.508 0.3048)
			(stroke
				(width 0.1)
				(type default)
			)
			(layer "F.Fab")
		)
		(pad "1" smd rect
			(at -0.5334 0 180)
			(size 0.7112 0.6096)
			(layers "F.Cu" "F.Mask" "F.Paste")
			(net "FPGA_CFG_INIT_N")
		)
		(pad "2" smd rect
			(at 0.5334 0 180)
			(size 0.7112 0.6096)
			(layers "F.Cu" "F.Mask" "F.Paste")
			(net "UNNAMED_515_NCP45560IMNTWGHDFN1")
		)
		(zone
			(layer "F.Cu")
			(hatch none 0.5)
			(connect_pads
				(clearance 0)
			)
			(min_thickness 0.25)
			(keepout
				(tracks allowed)
				(vias not_allowed)
				(pads allowed)
				(copperpour not_allowed)
				(footprints allowed)
			)
			(placement
				(enabled no)
				(sheetname "")
			)
			(fill
				(thermal_gap 0.5)
				(thermal_bridge_width 0.5)
				(island_removal_mode 0)
			)
			(polygon
				(pts
					(xy 115.3668 -76.3778) (xy 115.3668 -75.7682) (xy 115.5192 -75.7682) (xy 115.5192 -76.3778)
				)
			)
		)
	)
	(footprint ""
		(layer "F.Cu")
		(at 66.802 -123.698)
		(property "Reference" "SP38"
			(at 0 0 0)
			(layer "F.SilkS")
			(hide yes)
			(effects
				(font
					(size 1.27 1.27)
				)
			)
		)
		(property "Value" ""
			(at 0 0 0)
			(layer "F.Fab")
			(effects
				(font
					(size 1.27 1.27)
				)
			)
		)
		(duplicate_pad_numbers_are_jumpers no)
	)
)
